(kicad_pcb
	(version 20241229)
	(generator "pcbnew")
	(generator_version "9.0")
	(general
		(thickness 1.6642)
		(legacy_teardrops no)
	)
	(paper "A3")
	(title_block
		(title "PolarFire SoM")
		(date "2025-07-22")
		(rev "1.1.4")
		(company "Antmicro Ltd")
		(comment 1 "www.antmicro.com")
		(comment 9 "footprints 107-110 of 470")
	)
	(layers
		(0 "F.Cu" mixed)
		(4 "In1.Cu" power)
		(6 "In2.Cu" signal)
		(8 "In3.Cu" power)
		(10 "In4.Cu" signal)
		(12 "In5.Cu" power)
		(14 "In6.Cu" power)
		(16 "In7.Cu" signal)
		(18 "In8.Cu" power)
		(20 "In9.Cu" signal)
		(22 "In10.Cu" power)
		(24 "In11.Cu" signal)
		(26 "In12.Cu" signal)
		(2 "B.Cu" mixed)
		(9 "F.Adhes" user "F.Adhesive")
		(11 "B.Adhes" user "B.Adhesive")
		(13 "F.Paste" user)
		(15 "B.Paste" user)
		(5 "F.SilkS" user "F.Silkscreen")
		(7 "B.SilkS" user "B.Silkscreen")
		(1 "F.Mask" user)
		(3 "B.Mask" user)
		(17 "Dwgs.User" user "User.Drawings")
		(19 "Cmts.User" user "User.Comments")
		(21 "Eco1.User" user "User.Eco1")
		(23 "Eco2.User" user "User.Eco2")
		(25 "Edge.Cuts" user)
		(27 "Margin" user)
		(31 "F.CrtYd" user "F.Courtyard")
		(29 "B.CrtYd" user "B.Courtyard")
		(35 "F.Fab" user)
		(33 "B.Fab" user)
	)
	(footprint "antmicro-footprints:UQFN-10_1.4x1.8x0.5mm_P0.4mm"
		(layer "F.Cu")
		(at 212.533 153.0715)
		(property "Reference" "U22"
			(at 1.527 -0.4115 90)
			(layer "F.SilkS")
			(effects
				(font
					(size 0.7 0.7)
					(thickness 0.15)
				)
				(justify left bottom)
			)
		)
		(property "Value" "PI3USB102GZLEX"
			(at 0 2.4 0)
			(layer "F.Fab")
			(hide yes)
			(effects
				(font
					(size 0.7 0.7)
					(thickness 0.15)
				)
				(justify left bottom)
			)
		)
		(property "Datasheet" "https://www.diodes.com/assets/Datasheets/PI3USB102G.pdf"
			(at 0 0 0)
			(layer "F.Fab")
			(hide yes)
			(effects
				(font
					(size 1.27 1.27)
					(thickness 0.15)
				)
			)
		)
		(property "Description" "USB Switch IC 1 Channel 10-TQFN (1.3x1.6)"
			(at 0 0 0)
			(layer "F.Fab")
			(hide yes)
			(effects
				(font
					(size 1.27 1.27)
					(thickness 0.15)
				)
			)
		)
		(property "Author" "Antmicro"
			(at 0 0 0)
			(layer "F.Fab")
			(hide yes)
			(effects
				(font
					(size 1 1)
					(thickness 0.15)
				)
			)
		)
		(property "License" "Apache-2.0"
			(at 0 0 0)
			(layer "F.Fab")
			(hide yes)
			(effects
				(font
					(size 1 1)
					(thickness 0.15)
				)
			)
		)
		(property "MPN" "PI3USB102GZLEX"
			(at 0 0 0)
			(layer "F.Fab")
			(hide yes)
			(effects
				(font
					(size 1 1)
					(thickness 0.15)
				)
			)
		)
		(property "Manufacturer" "Diodes Incorporated"
			(at 0 0 0)
			(layer "F.Fab")
			(hide yes)
			(effects
				(font
					(size 1 1)
					(thickness 0.15)
				)
			)
		)
		(property ki_fp_filters "MSOP*3x3mm*P0.5mm*")
		(sheetname "/USB/")
		(sheetfile "usb.kicad_sch")
		(attr smd)
		(fp_line
			(start -0.7305 -0.552)
			(end -1.2005 -0.552)
			(stroke
				(width 0.15)
				(type solid)
			)
			(layer "F.SilkS")
		)
		(fp_line
			(start -0.7305 -0.552)
			(end -0.7305 -0.93)
			(stroke
				(width 0.15)
				(type solid)
			)
			(layer "F.SilkS")
		)
		(fp_circle
			(center -1.0515 -1.151)
			(end -0.9805 -1.151)
			(stroke
				(width 0.15)
				(type solid)
			)
			(fill no)
			(layer "F.SilkS")
		)
		(fp_rect
			(start -1.3 -1.5)
			(end 1.3 1.5)
			(stroke
				(width 0.05)
				(type solid)
			)
			(fill no)
			(layer "F.CrtYd")
		)
		(fp_line
			(start -0.7 -0.4)
			(end -0.175 -0.925)
			(stroke
				(width 0.15)
				(type solid)
			)
			(layer "F.Fab")
		)
		(fp_line
			(start -0.7 0.93)
			(end -0.7 -0.4)
			(stroke
				(width 0.15)
				(type solid)
			)
			(layer "F.Fab")
		)
		(fp_line
			(start -0.175 -0.925)
			(end 0.7295 -0.925)
			(stroke
				(width 0.15)
				(type solid)
			)
			(layer "F.Fab")
		)
		(fp_line
			(start 0.725 0.93)
			(end -0.7 0.93)
			(stroke
				(width 0.15)
				(type solid)
			)
			(layer "F.Fab")
		)
		(fp_line
			(start 0.7295 -0.925)
			(end 0.725 0.93)
			(stroke
				(width 0.15)
				(type solid)
			)
			(layer "F.Fab")
		)
		(fp_text user "License: Apache-2.0"
			(at -0.657 6.9 0)
			(layer "F.Fab")
			(effects
				(font
					(size 0.7 0.7)
					(thickness 0.15)
				)
				(justify left bottom)
			)
		)
		(fp_text user "${REFERENCE}"
			(at -0.657 4.498 0)
			(layer "F.Fab")
			(effects
				(font
					(size 0.7 0.7)
					(thickness 0.15)
				)
				(justify left bottom)
			)
		)
		(fp_text user "Author: Antmicro"
			(at -0.657 5.7 0)
			(layer "F.Fab")
			(effects
				(font
					(size 0.7 0.7)
					(thickness 0.15)
				)
				(justify left bottom)
			)
		)
		(pad "1" smd roundrect
			(at -0.6445 -0.2)
			(size 0.81 0.22)
			(layers "F.Cu" "F.Mask" "F.Paste")
			(roundrect_rratio 0.25)
			(net 16 "/Bottom Connector/CONN.D_P")
			(pinfunction "D+")
			(pintype "bidirectional")
		)
		(pad "2" smd roundrect
			(at -0.6445 0.2)
			(size 0.81 0.22)
			(layers "F.Cu" "F.Mask" "F.Paste")
			(roundrect_rratio 0.25)
			(net 15 "/Bottom Connector/CONN.D_N")
			(pinfunction "D-")
			(pintype "bidirectional")
		)
		(pad "3" smd roundrect
			(at -0.4015 0.844 270)
			(size 0.81 0.22)
			(layers "F.Cu" "F.Mask" "F.Paste")
			(roundrect_rratio 0.25)
			(net 417 "GND")
			(pinfunction "GND")
			(pintype "power_in")
		)
		(pad "4" smd roundrect
			(at 0.0005 0.844 270)
			(size 0.81 0.22)
			(layers "F.Cu" "F.Mask" "F.Paste")
			(roundrect_rratio 0.25)
			(net 514 "/USB/USB_DN1_N")
			(pinfunction "D1-")
			(pintype "bidirectional")
		)
		(pad "5" smd roundrect
			(at 0.3995 0.844 270)
			(size 0.81 0.22)
			(layers "F.Cu" "F.Mask" "F.Paste")
			(roundrect_rratio 0.25)
			(net 515 "/USB/USB_DN1_P")
			(pinfunction "D1+")
			(pintype "bidirectional")
		)
		(pad "6" smd roundrect
			(at 0.6455 0.2)
			(size 0.81 0.22)
			(layers "F.Cu" "F.Mask" "F.Paste")
			(roundrect_rratio 0.25)
			(net 510 "/USB/USB_BYP_N")
			(pinfunction "D2-")
			(pintype "bidirectional")
		)
		(pad "7" smd roundrect
			(at 0.6455 -0.2)
			(size 0.81 0.22)
			(layers "F.Cu" "F.Mask" "F.Paste")
			(roundrect_rratio 0.25)
			(net 511 "/USB/USB_BYP_P")
			(pinfunction "D2+")
			(pintype "bidirectional")
		)
		(pad "8" smd roundrect
			(at 0.3995 -0.847 270)
			(size 0.81 0.22)
			(layers "F.Cu" "F.Mask" "F.Paste")
			(roundrect_rratio 0.25)
			(net 417 "GND")
			(pinfunction "~{OE}")
			(pintype "input")
		)
		(pad "9" smd roundrect
			(at 0.0005 -0.847 270)
			(size 0.81 0.22)
			(layers "F.Cu" "F.Mask" "F.Paste")
			(roundrect_rratio 0.25)
			(net 50 "+3V3")
			(pinfunction "V_{DD}")
			(pintype "power_in")
		)
		(pad "10" smd roundrect
			(at -0.4015 -0.847 270)
			(size 0.81 0.22)
			(layers "F.Cu" "F.Mask" "F.Paste")
			(roundrect_rratio 0.25)
			(net 62 "USB_OTG_ID")
			(pinfunction "SEL")
			(pintype "input")
		)
	)
	(footprint "antmicro-footprints:C_0402_1005Metric"
		(layer "F.Cu")
		(at 175.475 142.9675 -90)
		(descr "Capacitor SMD 0402")
		(tags "capacitor SMD 0402")
		(property "Reference" "C102"
			(at 0.8825 -0.465 90)
			(layer "F.SilkS")
			(effects
				(font
					(size 0.7 0.7)
					(thickness 0.15)
				)
				(justify right bottom)
			)
		)
		(property "Value" "C_22u_0402"
			(at -1.022927 2.155213 90)
			(layer "F.Fab")
			(hide yes)
			(effects
				(font
					(size 0.7 0.7)
					(thickness 0.15)
				)
				(justify right bottom)
			)
		)
		(property "Datasheet" "https://www.murata.com/products/productdetail?partno=GRM158R60J226ME01%23"
			(at 0 0 270)
			(layer "F.Fab")
			(hide yes)
			(effects
				(font
					(size 1.27 1.27)
					(thickness 0.15)
				)
			)
		)
		(property "Description" "SMD Multilayer Ceramic Capacitor, 22 uF, 4 V, 0402 [1005 Metric], X6S"
			(at 0 0 270)
			(layer "F.Fab")
			(hide yes)
			(effects
				(font
					(size 1.27 1.27)
					(thickness 0.15)
				)
			)
		)
		(property "Author" "Antmicro"
			(at 32.5075 318.4425 0)
			(layer "F.Fab")
			(hide yes)
			(effects
				(font
					(size 1 1)
					(thickness 0.15)
				)
			)
		)
		(property "Dielectric" ""
			(at 32.5075 318.4425 0)
			(layer "F.Fab")
			(hide yes)
			(effects
				(font
					(size 1 1)
					(thickness 0.15)
				)
			)
		)
		(property "License" "Apache-2.0"
			(at 32.5075 318.4425 0)
			(layer "F.Fab")
			(hide yes)
			(effects
				(font
					(size 1 1)
					(thickness 0.15)
				)
			)
		)
		(property "MPN" "GRM158R60J226ME01D"
			(at 32.5075 318.4425 0)
			(layer "F.Fab")
			(hide yes)
			(effects
				(font
					(size 1 1)
					(thickness 0.15)
				)
			)
		)
		(property "Manufacturer" "Murata"
			(at 32.5075 318.4425 0)
			(layer "F.Fab")
			(hide yes)
			(effects
				(font
					(size 1 1)
					(thickness 0.15)
				)
			)
		)
		(property "Public" ""
			(at 32.5075 318.4425 0)
			(layer "F.Fab")
			(hide yes)
			(effects
				(font
					(size 1 1)
					(thickness 0.15)
				)
			)
		)
		(property "Val" "22u"
			(at 32.5075 318.4425 0)
			(layer "F.Fab")
			(hide yes)
			(effects
				(font
					(size 1 1)
					(thickness 0.15)
				)
			)
		)
		(property "Voltage" ""
			(at 32.5075 318.4425 0)
			(layer "F.Fab")
			(hide yes)
			(effects
				(font
					(size 1 1)
					(thickness 0.15)
				)
			)
		)
		(sheetname "/Supply/")
		(sheetfile "supply.kicad_sch")
		(attr smd)
		(fp_rect
			(start -0.925 -0.47)
			(end 0.925 0.47)
			(stroke
				(width 0.05)
				(type default)
			)
			(fill no)
			(layer "F.CrtYd")
		)
		(fp_line
			(start -0.494 0.248)
			(end -0.494 -0.25)
			(stroke
				(width 0.15)
				(type solid)
			)
			(layer "F.Fab")
		)
		(fp_line
			(start 0.504 0.248)
			(end -0.494 0.248)
			(stroke
				(width 0.15)
				(type solid)
			)
			(layer "F.Fab")
		)
		(fp_line
			(start -0.494 -0.25)
			(end 0.504 -0.25)
			(stroke
				(width 0.15)
				(type solid)
			)
			(layer "F.Fab")
		)
		(fp_line
			(start 0.504 -0.25)
			(end 0.504 0.248)
			(stroke
				(width 0.15)
				(type solid)
			)
			(layer "F.Fab")
		)
		(fp_text user "License: Apache-2.0"
			(at -0.939 5.799 270)
			(layer "F.Fab")
			(effects
				(font
					(size 0.7 0.7)
					(thickness 0.15)
				)
				(justify left bottom)
			)
		)
		(fp_text user "${REFERENCE}"
			(at -0.939 4.599 270)
			(layer "F.Fab")
			(effects
				(font
					(size 0.7 0.7)
					(thickness 0.15)
				)
				(justify left bottom)
			)
		)
		(fp_text user "Author: Antmicro"
			(at -0.939 3.399 270)
			(layer "F.Fab")
			(effects
				(font
					(size 0.7 0.7)
					(thickness 0.15)
				)
				(justify left bottom)
			)
		)
		(pad "1" smd roundrect
			(at -0.48 0 270)
			(size 0.59 0.64)
			(layers "F.Cu" "F.Mask" "F.Paste")
			(roundrect_rratio 0.25)
			(net 417 "GND")
			(pintype "passive")
		)
		(pad "2" smd roundrect
			(at 0.48 0 270)
			(size 0.59 0.64)
			(layers "F.Cu" "F.Mask" "F.Paste")
			(roundrect_rratio 0.25)
			(net 406 "/Supply/SENSE2_P")
			(pintype "passive")
		)
	)
	(footprint "antmicro-footprints:C_0402_1005Metric"
		(layer "F.Cu")
		(at 187.684904 147.897281 -90)
		(descr "Capacitor SMD 0402")
		(tags "capacitor SMD 0402")
		(property "Reference" "C105"
			(at 3.06272 -5.315096 180)
			(layer "F.SilkS")
			(effects
				(font
					(size 0.7 0.7)
					(thickness 0.15)
				)
				(justify right bottom)
			)
		)
		(property "Value" "C_22u_0402"
			(at -1.022927 2.155213 90)
			(layer "F.Fab")
			(hide yes)
			(effects
				(font
					(size 0.7 0.7)
					(thickness 0.15)
				)
				(justify right bottom)
			)
		)
		(property "Datasheet" "https://www.murata.com/products/productdetail?partno=GRM158R60J226ME01%23"
			(at 0 0 270)
			(layer "F.Fab")
			(hide yes)
			(effects
				(font
					(size 1.27 1.27)
					(thickness 0.15)
				)
			)
		)
		(property "Description" "SMD Multilayer Ceramic Capacitor, 22 uF, 4 V, 0402 [1005 Metric], X6S"
			(at 0 0 270)
			(layer "F.Fab")
			(hide yes)
			(effects
				(font
					(size 1.27 1.27)
					(thickness 0.15)
				)
			)
		)
		(property "Author" "Antmicro"
			(at 39.787623 335.582185 0)
			(layer "F.Fab")
			(hide yes)
			(effects
				(font
					(size 1 1)
					(thickness 0.15)
				)
			)
		)
		(property "Dielectric" ""
			(at 39.787623 335.582185 0)
			(layer "F.Fab")
			(hide yes)
			(effects
				(font
					(size 1 1)
					(thickness 0.15)
				)
			)
		)
		(property "License" "Apache-2.0"
			(at 39.787623 335.582185 0)
			(layer "F.Fab")
			(hide yes)
			(effects
				(font
					(size 1 1)
					(thickness 0.15)
				)
			)
		)
		(property "MPN" "GRM158R60J226ME01D"
			(at 39.787623 335.582185 0)
			(layer "F.Fab")
			(hide yes)
			(effects
				(font
					(size 1 1)
					(thickness 0.15)
				)
			)
		)
		(property "Manufacturer" "Murata"
			(at 39.787623 335.582185 0)
			(layer "F.Fab")
			(hide yes)
			(effects
				(font
					(size 1 1)
					(thickness 0.15)
				)
			)
		)
		(property "Public" ""
			(at 39.787623 335.582185 0)
			(layer "F.Fab")
			(hide yes)
			(effects
				(font
					(size 1 1)
					(thickness 0.15)
				)
			)
		)
		(property "Val" "22u"
			(at 39.787623 335.582185 0)
			(layer "F.Fab")
			(hide yes)
			(effects
				(font
					(size 1 1)
					(thickness 0.15)
				)
			)
		)
		(property "Voltage" ""
			(at 39.787623 335.582185 0)
			(layer "F.Fab")
			(hide yes)
			(effects
				(font
					(size 1 1)
					(thickness 0.15)
				)
			)
		)
		(sheetname "/Supply/")
		(sheetfile "supply.kicad_sch")
		(attr smd)
		(fp_rect
			(start -0.925 -0.47)
			(end 0.925 0.47)
			(stroke
				(width 0.05)
				(type default)
			)
			(fill no)
			(layer "F.CrtYd")
		)
		(fp_line
			(start -0.494 0.248)
			(end -0.494 -0.25)
			(stroke
				(width 0.15)
				(type solid)
			)
			(layer "F.Fab")
		)
		(fp_line
			(start 0.504 0.248)
			(end -0.494 0.248)
			(stroke
				(width 0.15)
				(type solid)
			)
			(layer "F.Fab")
		)
		(fp_line
			(start -0.494 -0.25)
			(end 0.504 -0.25)
			(stroke
				(width 0.15)
				(type solid)
			)
			(layer "F.Fab")
		)
		(fp_line
			(start 0.504 -0.25)
			(end 0.504 0.248)
			(stroke
				(width 0.15)
				(type solid)
			)
			(layer "F.Fab")
		)
		(fp_text user "Author: Antmicro"
			(at -0.939 3.399 270)
			(layer "F.Fab")
			(effects
				(font
					(size 0.7 0.7)
					(thickness 0.15)
				)
				(justify left bottom)
			)
		)
		(fp_text user "${REFERENCE}"
			(at -0.939 4.599 270)
			(layer "F.Fab")
			(effects
				(font
					(size 0.7 0.7)
					(thickness 0.15)
				)
				(justify left bottom)
			)
		)
		(fp_text user "License: Apache-2.0"
			(at -0.939 5.799 270)
			(layer "F.Fab")
			(effects
				(font
					(size 0.7 0.7)
					(thickness 0.15)
				)
				(justify left bottom)
			)
		)
		(pad "1" smd roundrect
			(at -0.48 0 270)
			(size 0.59 0.64)
			(layers "F.Cu" "F.Mask" "F.Paste")
			(roundrect_rratio 0.25)
			(net 417 "GND")
			(pintype "passive")
		)
		(pad "2" smd roundrect
			(at 0.48 0 270)
			(size 0.59 0.64)
			(layers "F.Cu" "F.Mask" "F.Paste")
			(roundrect_rratio 0.25)
			(net 522 "/Supply/1V05_REG")
			(pintype "passive")
		)
	)
	(footprint "antmicro-footprints:Coax_Conn_U.FL"
		(layer "F.Cu")
		(at 226.9 137.208)
		(descr "https://media.digikey.com/pdf/Data%20Sheets/Hirose%20PDFs/UFL%20Series.pdf")
		(property "Reference" "J3"
			(at 0.84 -2.138 0)
			(layer "F.SilkS")
			(effects
				(font
					(size 0.7 0.7)
					(thickness 0.15)
				)
				(justify left bottom)
			)
		)
		(property "Value" "U_FL-R-SMT-1"
			(at -4.13 2.52 0)
			(layer "F.Fab")
			(hide yes)
			(effects
				(font
					(size 0.7 0.7)
					(thickness 0.15)
				)
				(justify left bottom)
			)
		)
		(property "Datasheet" "https://media.digikey.com/pdf/Data%20Sheets/Hirose%20PDFs/UFL%20Series.pdf"
			(at 0 0 0)
			(layer "F.Fab")
			(hide yes)
			(effects
				(font
					(size 1.27 1.27)
					(thickness 0.15)
				)
			)
		)
		(property "Description" "U.FL (UMCC) Connector Receptacle, Male Pin 50Ohm Surface Mount Solder"
			(at 0 0 0)
			(layer "F.Fab")
			(hide yes)
			(effects
				(font
					(size 1.27 1.27)
					(thickness 0.15)
				)
			)
		)
		(property "Author" "Antmicro"
			(at 0 0 0)
			(layer "F.Fab")
			(hide yes)
			(effects
				(font
					(size 1 1)
					(thickness 0.15)
				)
			)
		)
		(property "License" "Apache-2.0"
			(at 0 0 0)
			(layer "F.Fab")
			(hide yes)
			(effects
				(font
					(size 1 1)
					(thickness 0.15)
				)
			)
		)
		(property "MPN" "U.FL-R-SMT-1(10)"
			(at 0 0 0)
			(layer "F.Fab")
			(hide yes)
			(effects
				(font
					(size 1 1)
					(thickness 0.15)
				)
			)
		)
		(property "Manufacturer" "Hirose Electric"
			(at 0 0 0)
			(layer "F.Fab")
			(hide yes)
			(effects
				(font
					(size 1 1)
					(thickness 0.15)
				)
			)
		)
		(sheetname "/WiFi_Bluetooth/")
		(sheetfile "wifi_bt.kicad_sch")
		(attr smd)
		(fp_line
			(start -1.613 -1.651)
			(end -1.613 -1.325)
			(stroke
				(width 0.15)
				(type solid)
			)
			(layer "F.SilkS")
		)
		(fp_line
			(start -1.613 -1.651)
			(end -1.113 -1.651)
			(stroke
				(width 0.15)
				(type solid)
			)
			(layer "F.SilkS")
		)
		(fp_line
			(start -1.613 1.648)
			(end -1.613 1.325)
			(stroke
				(width 0.15)
				(type solid)
			)
			(layer "F.SilkS")
		)
		(fp_line
			(start -1.613 1.648)
			(end -1.113 1.648)
			(stroke
				(width 0.15)
				(type solid)
			)
			(layer "F.SilkS")
		)
		(fp_line
			(start 1.588 -1.651)
			(end 1.088 -1.651)
			(stroke
				(width 0.15)
				(type solid)
			)
			(layer "F.SilkS")
		)
		(fp_line
			(start 1.588 -1.651)
			(end 1.588 -1.325)
			(stroke
				(width 0.15)
				(type solid)
			)
			(layer "F.SilkS")
		)
		(fp_line
			(start 1.588 1.648)
			(end 1.088 1.648)
			(stroke
				(width 0.15)
				(type solid)
			)
			(layer "F.SilkS")
		)
		(fp_line
			(start 1.588 1.648)
			(end 1.588 1.325)
			(stroke
				(width 0.15)
				(type solid)
			)
			(layer "F.SilkS")
		)
		(fp_rect
			(start -2 -2.051)
			(end 1.999 2.05)
			(stroke
				(width 0.05)
				(type solid)
			)
			(fill no)
			(layer "F.CrtYd")
		)
		(fp_line
			(start -1.512 -1.551)
			(end 1.487 -1.551)
			(stroke
				(width 0.15)
				(type solid)
			)
			(layer "F.Fab")
		)
		(fp_line
			(start -1.512 1.55)
			(end -1.512 -1.551)
			(stroke
				(width 0.15)
				(type solid)
			)
			(layer "F.Fab")
		)
		(fp_line
			(start -1.512 1.55)
			(end 1.487 1.55)
			(stroke
				(width 0.15)
				(type solid)
			)
			(layer "F.Fab")
		)
		(fp_line
			(start 1.487 1.55)
			(end 1.487 -1.551)
			(stroke
				(width 0.15)
				(type solid)
			)
			(layer "F.Fab")
		)
		(fp_text user "${REFERENCE}"
			(at -4.13 6.92 0)
			(layer "F.Fab")
			(effects
				(font
					(size 0.7 0.7)
					(thickness 0.15)
				)
				(justify left bottom)
			)
		)
		(fp_text user "Author: Antmicro"
			(at -4.13 4.52 0)
			(layer "F.Fab")
			(effects
				(font
					(size 0.7 0.7)
					(thickness 0.15)
				)
				(justify left bottom)
			)
		)
		(fp_text user "License: Apache-2.0"
			(at -4.13 5.72 0)
			(layer "F.Fab")
			(effects
				(font
					(size 0.7 0.7)
					(thickness 0.15)
				)
				(justify left bottom)
			)
		)
		(pad "1" smd rect
			(at -0.012 1.499)
			(size 1 1.05)
			(layers "F.Cu" "F.Mask" "F.Paste")
			(net 178 "Net-(J3-Pad1)")
			(pintype "passive")
		)
		(pad "SH1" smd rect
			(at 1.463 0)
			(size 1.05 2.2)
			(layers "F.Cu" "F.Mask" "F.Paste")
			(net 417 "GND")
			(pintype "passive")
		)
		(pad "SH2" smd rect
			(at -1.488 0)
			(size 1.05 2.2)
			(layers "F.Cu" "F.Mask" "F.Paste")
			(net 417 "GND")
			(pintype "passive")
		)
		(zone
			(net 0)
			(net_name "")
			(layer "F.Cu")
			(hatch edge 0.508)
			(connect_pads
				(clearance 0)
			)
			(min_thickness 0.254)
			(filled_areas_thickness no)
			(keepout
				(tracks not_allowed)
				(vias not_allowed)
				(pads not_allowed)
				(copperpour not_allowed)
				(footprints not_allowed)
			)
			(placement
				(enabled no)
				(sheetname "")
			)
			(fill
				(thermal_gap 0.508)
				(thermal_bridge_width 0.508)
			)
			(polygon
				(pts
					(xy 227.83 138.168) (xy 225.95 138.168) (xy 225.95 136.108) (xy 227.83 136.108)
				)
			)
		)
	)
)
